(kicad_pcb
	(version 20260206)
	(generator "pcbnew")
	(generator_version "10.0")
	(general
		(thickness 1.6)
		(legacy_teardrops no)
	)
	(paper "A4")
	(title_block
		(title "03242023_DA0F0TMBIJ0_F0T_Motherboard_J_brd_V01_OCP.brd")
		(comment 1 "Grand Teton / footprints 1406-1411 of 6105")
	)
	(layers
		(0 "F.Cu" signal "TOP")
		(4 "In1.Cu" signal "GND")
		(6 "In2.Cu" signal "IN1")
		(8 "In3.Cu" signal "GND1")
		(10 "In4.Cu" signal "IN2")
		(12 "In5.Cu" signal "GND2")
		(14 "In6.Cu" signal "IN3")
		(16 "In7.Cu" signal "GND3")
		(18 "In8.Cu" signal "VCC")
		(20 "In9.Cu" signal "VCC1")
		(22 "In10.Cu" signal "GND4")
		(24 "In11.Cu" signal "IN4")
		(26 "In12.Cu" signal "GND5")
		(28 "In13.Cu" signal "IN5")
		(30 "In14.Cu" signal "GND6")
		(32 "In15.Cu" signal "IN6")
		(34 "In16.Cu" signal "GND7")
		(2 "B.Cu" signal "BOTTOM")
		(9 "F.Adhes" user "F.Adhesive")
		(11 "B.Adhes" user "B.Adhesive")
		(13 "F.Paste" user "Package Geometry/Pastemask Top")
		(15 "B.Paste" user "Package Geometry/Pastemask Bottom")
		(5 "F.SilkS" user "Ref Des/Silkscreen Top")
		(7 "B.SilkS" user "Ref Des/Silkscreen Bottom")
		(1 "F.Mask" user "Board Geometry/Soldermask Top")
		(3 "B.Mask" user "Board Geometry/Soldermask Bottom")
		(17 "Dwgs.User" user "User.Drawings")
		(19 "Cmts.User" user "User.Comments")
		(21 "Eco1.User" user "User.Eco1")
		(23 "Eco2.User" user "User.Eco2")
		(25 "Edge.Cuts" user "Board Geometry/Outline")
		(27 "Margin" user)
		(31 "F.CrtYd" user "Package Geometry/Place Bound Top")
		(29 "B.CrtYd" user "Package Geometry/Place Bound Bottom")
		(35 "F.Fab" user "Ref Des/Assembly Top")
		(33 "B.Fab" user "Ref Des/Assembly Bottom")
	)
	(footprint ""
		(layer "F.Cu")
		(at 131.318 -156.398468 180)
		(property "Reference" "R1495"
			(at 0 0 180)
			(layer "F.SilkS")
			(hide yes)
			(effects
				(font
					(size 1.27 1.27)
				)
			)
		)
		(property "Value" ""
			(at 0 0 180)
			(layer "F.Fab")
			(effects
				(font
					(size 1.27 1.27)
				)
			)
		)
		(duplicate_pad_numbers_are_jumpers no)
		(fp_line
			(start 0.7874 0.4064)
			(end -0.7874 0.4064)
			(stroke
				(width 0.1524)
				(type default)
			)
			(layer "F.SilkS")
		)
		(fp_line
			(start 0.7874 -0.4064)
			(end 0.7874 0.4064)
			(stroke
				(width 0.1524)
				(type default)
			)
			(layer "F.SilkS")
		)
		(fp_line
			(start -0.7874 0.4064)
			(end -0.7874 -0.4064)
			(stroke
				(width 0.1524)
				(type default)
			)
			(layer "F.SilkS")
		)
		(fp_line
			(start -0.7874 -0.4064)
			(end 0.7874 -0.4064)
			(stroke
				(width 0.1524)
				(type default)
			)
			(layer "F.SilkS")
		)
		(fp_line
			(start 0.67945 0.3048)
			(end 0.120396 0.3048)
			(stroke
				(width 0.1)
				(type default)
			)
			(layer "F.Fab")
		)
		(fp_line
			(start 0.67945 -0.3048)
			(end 0.67945 0.3048)
			(stroke
				(width 0.1)
				(type default)
			)
			(layer "F.Fab")
		)
		(fp_line
			(start 0.12065 -0.2794)
			(end 0.12065 -0.3048)
			(stroke
				(width 0.1)
				(type default)
			)
			(layer "F.Fab")
		)
		(fp_line
			(start 0.12065 -0.3048)
			(end 0.67945 -0.3048)
			(stroke
				(width 0.1)
				(type default)
			)
			(layer "F.Fab")
		)
		(fp_line
			(start 0.120396 0.3048)
			(end 0.120396 0.2794)
			(stroke
				(width 0.1)
				(type default)
			)
			(layer "F.Fab")
		)
		(fp_line
			(start 0.120396 0.2794)
			(end -0.12065 0.2794)
			(stroke
				(width 0.1)
				(type default)
			)
			(layer "F.Fab")
		)
		(fp_line
			(start -0.12065 0.3048)
			(end -0.67945 0.3048)
			(stroke
				(width 0.1)
				(type default)
			)
			(layer "F.Fab")
		)
		(fp_line
			(start -0.12065 0.2794)
			(end -0.12065 0.3048)
			(stroke
				(width 0.1)
				(type default)
			)
			(layer "F.Fab")
		)
		(fp_line
			(start -0.12065 -0.2794)
			(end 0.12065 -0.2794)
			(stroke
				(width 0.1)
				(type default)
			)
			(layer "F.Fab")
		)
		(fp_line
			(start -0.12065 -0.305054)
			(end -0.12065 -0.2794)
			(stroke
				(width 0.1)
				(type default)
			)
			(layer "F.Fab")
		)
		(fp_line
			(start -0.67945 0.3048)
			(end -0.67945 -0.305054)
			(stroke
				(width 0.1)
				(type default)
			)
			(layer "F.Fab")
		)
		(fp_line
			(start -0.67945 -0.305054)
			(end -0.12065 -0.305054)
			(stroke
				(width 0.1)
				(type default)
			)
			(layer "F.Fab")
		)
		(pad "1" smd circle
			(at -0.40005 0 180)
			(size 0 0)
			(layers "F.Cu" "F.Mask" "F.Paste")
			(net "PD_FORCE_PWRON")
		)
		(pad "2" smd circle
			(at 0.40005 0 180)
			(size 0 0)
			(layers "F.Cu" "F.Mask" "F.Paste")
			(net "GND")
		)
	)
	(footprint ""
		(layer "F.Cu")
		(at 142.54988 -46.954948)
		(property "Reference" "R5377"
			(at 0 0 0)
			(layer "F.SilkS")
			(hide yes)
			(effects
				(font
					(size 1.27 1.27)
				)
			)
		)
		(property "Value" ""
			(at 0 0 0)
			(layer "F.Fab")
			(effects
				(font
					(size 1.27 1.27)
				)
			)
		)
		(duplicate_pad_numbers_are_jumpers no)
		(fp_line
			(start -0.7874 -0.4064)
			(end 0.7874 -0.4064)
			(stroke
				(width 0.1524)
				(type default)
			)
			(layer "F.SilkS")
		)
		(fp_line
			(start -0.7874 0.4064)
			(end -0.7874 -0.4064)
			(stroke
				(width 0.1524)
				(type default)
			)
			(layer "F.SilkS")
		)
		(fp_line
			(start 0.7874 -0.4064)
			(end 0.7874 0.4064)
			(stroke
				(width 0.1524)
				(type default)
			)
			(layer "F.SilkS")
		)
		(fp_line
			(start 0.7874 0.4064)
			(end -0.7874 0.4064)
			(stroke
				(width 0.1524)
				(type default)
			)
			(layer "F.SilkS")
		)
		(fp_line
			(start -0.67945 -0.305054)
			(end -0.12065 -0.305054)
			(stroke
				(width 0.1)
				(type default)
			)
			(layer "F.Fab")
		)
		(fp_line
			(start -0.67945 0.3048)
			(end -0.67945 -0.305054)
			(stroke
				(width 0.1)
				(type default)
			)
			(layer "F.Fab")
		)
		(fp_line
			(start -0.12065 -0.305054)
			(end -0.12065 -0.2794)
			(stroke
				(width 0.1)
				(type default)
			)
			(layer "F.Fab")
		)
		(fp_line
			(start -0.12065 -0.2794)
			(end 0.12065 -0.2794)
			(stroke
				(width 0.1)
				(type default)
			)
			(layer "F.Fab")
		)
		(fp_line
			(start -0.12065 0.2794)
			(end -0.12065 0.3048)
			(stroke
				(width 0.1)
				(type default)
			)
			(layer "F.Fab")
		)
		(fp_line
			(start -0.12065 0.3048)
			(end -0.67945 0.3048)
			(stroke
				(width 0.1)
				(type default)
			)
			(layer "F.Fab")
		)
		(fp_line
			(start 0.120396 0.2794)
			(end -0.12065 0.2794)
			(stroke
				(width 0.1)
				(type default)
			)
			(layer "F.Fab")
		)
		(fp_line
			(start 0.120396 0.3048)
			(end 0.120396 0.2794)
			(stroke
				(width 0.1)
				(type default)
			)
			(layer "F.Fab")
		)
		(fp_line
			(start 0.12065 -0.3048)
			(end 0.67945 -0.3048)
			(stroke
				(width 0.1)
				(type default)
			)
			(layer "F.Fab")
		)
		(fp_line
			(start 0.12065 -0.2794)
			(end 0.12065 -0.3048)
			(stroke
				(width 0.1)
				(type default)
			)
			(layer "F.Fab")
		)
		(fp_line
			(start 0.67945 -0.3048)
			(end 0.67945 0.3048)
			(stroke
				(width 0.1)
				(type default)
			)
			(layer "F.Fab")
		)
		(fp_line
			(start 0.67945 0.3048)
			(end 0.120396 0.3048)
			(stroke
				(width 0.1)
				(type default)
			)
			(layer "F.Fab")
		)
		(pad "1" smd circle
			(at -0.40005 0)
			(size 0 0)
			(layers "F.Cu" "F.Mask" "F.Paste")
			(net "HDD_ACTIVITY_BUF_N")
		)
		(pad "2" smd circle
			(at 0.40005 0)
			(size 0 0)
			(layers "F.Cu" "F.Mask" "F.Paste")
			(net "PU_BUFFER_HDD_ACTIVITY")
		)
	)
	(footprint ""
		(layer "F.Cu")
		(at 148.197824 -50.388012)
		(property "Reference" "R3621"
			(at 0 0 0)
			(layer "F.SilkS")
			(hide yes)
			(effects
				(font
					(size 1.27 1.27)
				)
			)
		)
		(property "Value" ""
			(at 0 0 0)
			(layer "F.Fab")
			(effects
				(font
					(size 1.27 1.27)
				)
			)
		)
		(duplicate_pad_numbers_are_jumpers no)
		(fp_line
			(start -0.7874 -0.4064)
			(end 0.7874 -0.4064)
			(stroke
				(width 0.1524)
				(type default)
			)
			(layer "F.SilkS")
		)
		(fp_line
			(start -0.7874 0.4064)
			(end -0.7874 -0.4064)
			(stroke
				(width 0.1524)
				(type default)
			)
			(layer "F.SilkS")
		)
		(fp_line
			(start 0.7874 -0.4064)
			(end 0.7874 0.4064)
			(stroke
				(width 0.1524)
				(type default)
			)
			(layer "F.SilkS")
		)
		(fp_line
			(start 0.7874 0.4064)
			(end -0.7874 0.4064)
			(stroke
				(width 0.1524)
				(type default)
			)
			(layer "F.SilkS")
		)
		(fp_line
			(start -0.67945 -0.305054)
			(end -0.12065 -0.305054)
			(stroke
				(width 0.1)
				(type default)
			)
			(layer "F.Fab")
		)
		(fp_line
			(start -0.67945 0.3048)
			(end -0.67945 -0.305054)
			(stroke
				(width 0.1)
				(type default)
			)
			(layer "F.Fab")
		)
		(fp_line
			(start -0.12065 -0.305054)
			(end -0.12065 -0.2794)
			(stroke
				(width 0.1)
				(type default)
			)
			(layer "F.Fab")
		)
		(fp_line
			(start -0.12065 -0.2794)
			(end 0.12065 -0.2794)
			(stroke
				(width 0.1)
				(type default)
			)
			(layer "F.Fab")
		)
		(fp_line
			(start -0.12065 0.2794)
			(end -0.12065 0.3048)
			(stroke
				(width 0.1)
				(type default)
			)
			(layer "F.Fab")
		)
		(fp_line
			(start -0.12065 0.3048)
			(end -0.67945 0.3048)
			(stroke
				(width 0.1)
				(type default)
			)
			(layer "F.Fab")
		)
		(fp_line
			(start 0.120396 0.2794)
			(end -0.12065 0.2794)
			(stroke
				(width 0.1)
				(type default)
			)
			(layer "F.Fab")
		)
		(fp_line
			(start 0.120396 0.3048)
			(end 0.120396 0.2794)
			(stroke
				(width 0.1)
				(type default)
			)
			(layer "F.Fab")
		)
		(fp_line
			(start 0.12065 -0.3048)
			(end 0.67945 -0.3048)
			(stroke
				(width 0.1)
				(type default)
			)
			(layer "F.Fab")
		)
		(fp_line
			(start 0.12065 -0.2794)
			(end 0.12065 -0.3048)
			(stroke
				(width 0.1)
				(type default)
			)
			(layer "F.Fab")
		)
		(fp_line
			(start 0.67945 -0.3048)
			(end 0.67945 0.3048)
			(stroke
				(width 0.1)
				(type default)
			)
			(layer "F.Fab")
		)
		(fp_line
			(start 0.67945 0.3048)
			(end 0.120396 0.3048)
			(stroke
				(width 0.1)
				(type default)
			)
			(layer "F.Fab")
		)
		(pad "1" smd circle
			(at -0.40005 0)
			(size 0 0)
			(layers "F.Cu" "F.Mask" "F.Paste")
			(net "P3V3_AUX")
		)
		(pad "2" smd circle
			(at 0.40005 0)
			(size 0 0)
			(layers "F.Cu" "F.Mask" "F.Paste")
			(net "INA230_4_A0")
		)
	)
	(footprint ""
		(layer "F.Cu")
		(at 224.16262 -378.176028)
		(property "Reference" "ME22"
			(at -0.1016 -6.949948 0)
			(unlocked yes)
			(layer "F.SilkS")
			(effects
				(font
					(size 0.7874 0.5842)
					(thickness 0.1524)
				)
				(justify left)
			)
		)
		(property "Value" ""
			(at 0 0 0)
			(layer "F.Fab")
			(effects
				(font
					(size 1.27 1.27)
				)
			)
		)
		(duplicate_pad_numbers_are_jumpers no)
		(fp_line
			(start 0 -5.999988)
			(end 0 -4.475988)
			(stroke
				(width 0.1524)
				(type default)
			)
			(layer "F.SilkS")
		)
		(fp_line
			(start 0 -1.524)
			(end 0 0)
			(stroke
				(width 0.1524)
				(type default)
			)
			(layer "F.SilkS")
		)
		(fp_line
			(start 0 0)
			(end 1.524 0)
			(stroke
				(width 0.1524)
				(type default)
			)
			(layer "F.SilkS")
		)
		(fp_line
			(start 1.524 -5.999988)
			(end 0 -5.999988)
			(stroke
				(width 0.1524)
				(type default)
			)
			(layer "F.SilkS")
		)
		(fp_line
			(start 25.475946 -5.999988)
			(end 26.999946 -5.999988)
			(stroke
				(width 0.1524)
				(type default)
			)
			(layer "F.SilkS")
		)
		(fp_line
			(start 26.999946 -5.999988)
			(end 26.999946 -4.475988)
			(stroke
				(width 0.1524)
				(type default)
			)
			(layer "F.SilkS")
		)
		(fp_line
			(start 26.999946 -1.524)
			(end 26.999946 0)
			(stroke
				(width 0.1524)
				(type default)
			)
			(layer "F.SilkS")
		)
		(fp_line
			(start 26.999946 0)
			(end 25.475946 0)
			(stroke
				(width 0.1524)
				(type default)
			)
			(layer "F.SilkS")
		)
		(fp_text user "S/N"
			(at 0.2032 -4.59105 0)
			(unlocked yes)
			(layer "F.SilkS")
			(effects
				(font
					(size 1.905 1.4224)
					(thickness 0.1524)
				)
				(justify left)
			)
		)
	)
	(footprint ""
		(layer "F.Cu")
		(at 397.403066 -167.491664)
		(property "Reference" "PR591"
			(at 0 0 0)
			(layer "F.SilkS")
			(hide yes)
			(effects
				(font
					(size 1.27 1.27)
				)
			)
		)
		(property "Value" ""
			(at 0 0 0)
			(layer "F.Fab")
			(effects
				(font
					(size 1.27 1.27)
				)
			)
		)
		(duplicate_pad_numbers_are_jumpers no)
		(fp_line
			(start -0.7874 -0.4064)
			(end 0.7874 -0.4064)
			(stroke
				(width 0.1524)
				(type default)
			)
			(layer "F.SilkS")
		)
		(fp_line
			(start -0.7874 0.4064)
			(end -0.7874 -0.4064)
			(stroke
				(width 0.1524)
				(type default)
			)
			(layer "F.SilkS")
		)
		(fp_line
			(start 0.7874 -0.4064)
			(end 0.7874 0.4064)
			(stroke
				(width 0.1524)
				(type default)
			)
			(layer "F.SilkS")
		)
		(fp_line
			(start 0.7874 0.4064)
			(end -0.7874 0.4064)
			(stroke
				(width 0.1524)
				(type default)
			)
			(layer "F.SilkS")
		)
		(fp_line
			(start -0.67945 -0.305054)
			(end -0.12065 -0.305054)
			(stroke
				(width 0.1)
				(type default)
			)
			(layer "F.Fab")
		)
		(fp_line
			(start -0.67945 0.3048)
			(end -0.67945 -0.305054)
			(stroke
				(width 0.1)
				(type default)
			)
			(layer "F.Fab")
		)
		(fp_line
			(start -0.12065 -0.305054)
			(end -0.12065 -0.2794)
			(stroke
				(width 0.1)
				(type default)
			)
			(layer "F.Fab")
		)
		(fp_line
			(start -0.12065 -0.2794)
			(end 0.12065 -0.2794)
			(stroke
				(width 0.1)
				(type default)
			)
			(layer "F.Fab")
		)
		(fp_line
			(start -0.12065 0.2794)
			(end -0.12065 0.3048)
			(stroke
				(width 0.1)
				(type default)
			)
			(layer "F.Fab")
		)
		(fp_line
			(start -0.12065 0.3048)
			(end -0.67945 0.3048)
			(stroke
				(width 0.1)
				(type default)
			)
			(layer "F.Fab")
		)
		(fp_line
			(start 0.120396 0.2794)
			(end -0.12065 0.2794)
			(stroke
				(width 0.1)
				(type default)
			)
			(layer "F.Fab")
		)
		(fp_line
			(start 0.120396 0.3048)
			(end 0.120396 0.2794)
			(stroke
				(width 0.1)
				(type default)
			)
			(layer "F.Fab")
		)
		(fp_line
			(start 0.12065 -0.3048)
			(end 0.67945 -0.3048)
			(stroke
				(width 0.1)
				(type default)
			)
			(layer "F.Fab")
		)
		(fp_line
			(start 0.12065 -0.2794)
			(end 0.12065 -0.3048)
			(stroke
				(width 0.1)
				(type default)
			)
			(layer "F.Fab")
		)
		(fp_line
			(start 0.67945 -0.3048)
			(end 0.67945 0.3048)
			(stroke
				(width 0.1)
				(type default)
			)
			(layer "F.Fab")
		)
		(fp_line
			(start 0.67945 0.3048)
			(end 0.120396 0.3048)
			(stroke
				(width 0.1)
				(type default)
			)
			(layer "F.Fab")
		)
		(pad "1" smd circle
			(at -0.40005 0)
			(size 0 0)
			(layers "F.Cu" "F.Mask" "F.Paste")
			(net "VSENSE_PVCCD_HV_CPU0_DN")
		)
		(pad "2" smd circle
			(at 0.40005 0)
			(size 0 0)
			(layers "F.Cu" "F.Mask" "F.Paste")
			(net "GND")
		)
	)
	(footprint ""
		(layer "F.Cu")
		(at 326.323198 -32.688022 -45)
		(property "Reference" "C1507"
			(at 0 0 315)
			(layer "F.SilkS")
			(hide yes)
			(effects
				(font
					(size 1.27 1.27)
				)
			)
		)
		(property "Value" ""
			(at 0 0 315)
			(layer "F.Fab")
			(effects
				(font
					(size 1.27 1.27)
				)
			)
		)
		(duplicate_pad_numbers_are_jumpers no)
		(fp_line
			(start -0.787389 0.406267)
			(end -0.787389 -0.406267)
			(stroke
				(width 0.1524)
				(type default)
			)
			(layer "F.SilkS")
		)
		(fp_line
			(start -0.787389 -0.406267)
			(end 0.787389 -0.406267)
			(stroke
				(width 0.1524)
				(type default)
			)
			(layer "F.SilkS")
		)
		(fp_line
			(start 0.787389 0.406267)
			(end -0.787389 0.406267)
			(stroke
				(width 0.1524)
				(type default)
			)
			(layer "F.SilkS")
		)
		(fp_line
			(start 0.787389 -0.406267)
			(end 0.787389 0.406267)
			(stroke
				(width 0.1524)
				(type default)
			)
			(layer "F.SilkS")
		)
		(fp_line
			(start -0.679446 0.30479)
			(end -0.679446 -0.305149)
			(stroke
				(width 0.1)
				(type default)
			)
			(layer "F.Fab")
		)
		(fp_line
			(start -0.120515 0.30479)
			(end -0.679446 0.30479)
			(stroke
				(width 0.1)
				(type default)
			)
			(layer "F.Fab")
		)
		(fp_line
			(start -0.120695 0.279466)
			(end -0.120515 0.30479)
			(stroke
				(width 0.1)
				(type default)
			)
			(layer "F.Fab")
		)
		(fp_line
			(start -0.679446 -0.305149)
			(end -0.120695 -0.304969)
			(stroke
				(width 0.1)
				(type default)
			)
			(layer "F.Fab")
		)
		(fp_line
			(start 0.120515 0.30479)
			(end 0.120335 0.279466)
			(stroke
				(width 0.1)
				(type default)
			)
			(layer "F.Fab")
		)
		(fp_line
			(start 0.120335 0.279466)
			(end -0.120695 0.279466)
			(stroke
				(width 0.1)
				(type default)
			)
			(layer "F.Fab")
		)
		(fp_line
			(start -0.120695 -0.279466)
			(end 0.120695 -0.279466)
			(stroke
				(width 0.1)
				(type default)
			)
			(layer "F.Fab")
		)
		(fp_line
			(start -0.120695 -0.304969)
			(end -0.120695 -0.279466)
			(stroke
				(width 0.1)
				(type default)
			)
			(layer "F.Fab")
		)
		(fp_line
			(start 0.679446 0.30479)
			(end 0.120515 0.30479)
			(stroke
				(width 0.1)
				(type default)
			)
			(layer "F.Fab")
		)
		(fp_line
			(start 0.120695 -0.279466)
			(end 0.120515 -0.30479)
			(stroke
				(width 0.1)
				(type default)
			)
			(layer "F.Fab")
		)
		(fp_line
			(start 0.120515 -0.30479)
			(end 0.679446 -0.30479)
			(stroke
				(width 0.1)
				(type default)
			)
			(layer "F.Fab")
		)
		(fp_line
			(start 0.679446 -0.30479)
			(end 0.679446 0.30479)
			(stroke
				(width 0.1)
				(type default)
			)
			(layer "F.Fab")
		)
		(pad "1" smd circle
			(at -0.40005 0 315)
			(size 0 0)
			(layers "F.Cu" "F.Mask" "F.Paste")
			(net "XTAL_PCH_RTC2_R")
		)
		(pad "2" smd circle
			(at 0.40005 0 315)
			(size 0 0)
			(layers "F.Cu" "F.Mask" "F.Paste")
			(net "GND")
		)
	)
)
